# T6G (Grand Teton) — schematic netlist excerpt (pin names and nets, part order shuffled) for the footprints in the layout excerpt that follows; sources: Cadence DE-HDL packaged netlist, KiCad conversion of 04192023_DAF0TMB3IC0_F0TG_MB_C_brd_V02_OCP.brd

R586  Q_RES  1 1% CHIP  pkg 0603LF  page 183 : A = P3V3_9ZXL045_P1 ; B = P3V3_9ZXL045_P1_VDDA
C675  Q_CAP  0.1UF 25V 10% EMPTY  pkg 0402  page 226 : A = PVDD18_S5_P1_EN ; B = GND

(kicad_pcb
	(version 20260206)
	(generator "pcbnew")
	(generator_version "10.0")
	(general
		(thickness 1.6)
		(legacy_teardrops no)
	)
	(paper "A4")
	(title_block
		(title "04192023_DAF0TMB3IC0_F0TG_MB_C_brd_V02_OCP.brd")
		(comment 1 "Grand Teton / footprints 954-955 of 8354")
	)
	(layers
		(0 "F.Cu" signal "TOP")
		(4 "In1.Cu" signal "GND")
		(6 "In2.Cu" signal "IN1")
		(8 "In3.Cu" signal "GND1")
		(10 "In4.Cu" signal "IN2")
		(12 "In5.Cu" signal "GND2")
		(14 "In6.Cu" signal "IN3")
		(16 "In7.Cu" signal "GND3")
		(18 "In8.Cu" signal "VCC")
		(20 "In9.Cu" signal "VCC1")
		(22 "In10.Cu" signal "GND4")
		(24 "In11.Cu" signal "IN4")
		(26 "In12.Cu" signal "GND5")
		(28 "In13.Cu" signal "IN5")
		(30 "In14.Cu" signal "GND6")
		(32 "In15.Cu" signal "IN6")
		(34 "In16.Cu" signal "GND7")
		(2 "B.Cu" signal "BOTTOM")
		(9 "F.Adhes" user "F.Adhesive")
		(11 "B.Adhes" user "B.Adhesive")
		(13 "F.Paste" user "Package Geometry/Pastemask Top")
		(15 "B.Paste" user "Package Geometry/Pastemask Bottom")
		(5 "F.SilkS" user "Ref Des/Silkscreen Top")
		(7 "B.SilkS" user "Ref Des/Silkscreen Bottom")
		(1 "F.Mask" user "Board Geometry/Soldermask Top")
		(3 "B.Mask" user "Board Geometry/Soldermask Bottom")
		(17 "Dwgs.User" user "User.Drawings")
		(19 "Cmts.User" user "User.Comments")
		(21 "Eco1.User" user "User.Eco1")
		(23 "Eco2.User" user "User.Eco2")
		(25 "Edge.Cuts" user "Board Geometry/Outline")
		(27 "Margin" user)
		(31 "F.CrtYd" user "Package Geometry/Place Bound Top")
		(29 "B.CrtYd" user "Package Geometry/Place Bound Bottom")
		(35 "F.Fab" user "Ref Des/Assembly Top")
		(33 "B.Fab" user "Ref Des/Assembly Bottom")
	)
	(footprint ""
		(layer "F.Cu")
		(at 74.34707 -148.451316 -90)
		(property "Reference" "C675"
			(at 0 0 270)
			(layer "F.SilkS")
			(hide yes)
			(effects
				(font
					(size 1.27 1.27)
				)
			)
		)
		(property "Value" ""
			(at 0 0 270)
			(layer "F.Fab")
			(effects
				(font
					(size 1.27 1.27)
				)
			)
		)
		(duplicate_pad_numbers_are_jumpers no)
		(fp_line
			(start -0.7874 0.4064)
			(end -0.7874 -0.4064)
			(stroke
				(width 0.1524)
				(type default)
			)
			(layer "F.SilkS")
		)
		(fp_line
			(start 0.7874 0.4064)
			(end -0.7874 0.4064)
			(stroke
				(width 0.1524)
				(type default)
			)
			(layer "F.SilkS")
		)
		(fp_line
			(start -0.7874 -0.4064)
			(end 0.7874 -0.4064)
			(stroke
				(width 0.1524)
				(type default)
			)
			(layer "F.SilkS")
		)
		(fp_line
			(start 0.7874 -0.4064)
			(end 0.7874 0.4064)
			(stroke
				(width 0.1524)
				(type default)
			)
			(layer "F.SilkS")
		)
		(fp_line
			(start -0.67945 0.3048)
			(end -0.67945 -0.305054)
			(stroke
				(width 0.1)
				(type default)
			)
			(layer "F.Fab")
		)
		(fp_line
			(start -0.12065 0.3048)
			(end -0.67945 0.3048)
			(stroke
				(width 0.1)
				(type default)
			)
			(layer "F.Fab")
		)
		(fp_line
			(start 0.120396 0.3048)
			(end 0.120396 0.2794)
			(stroke
				(width 0.1)
				(type default)
			)
			(layer "F.Fab")
		)
		(fp_line
			(start 0.67945 0.3048)
			(end 0.120396 0.3048)
			(stroke
				(width 0.1)
				(type default)
			)
			(layer "F.Fab")
		)
		(fp_line
			(start -0.12065 0.2794)
			(end -0.12065 0.3048)
			(stroke
				(width 0.1)
				(type default)
			)
			(layer "F.Fab")
		)
		(fp_line
			(start 0.120396 0.2794)
			(end -0.12065 0.2794)
			(stroke
				(width 0.1)
				(type default)
			)
			(layer "F.Fab")
		)
		(fp_line
			(start -0.12065 -0.2794)
			(end 0.12065 -0.2794)
			(stroke
				(width 0.1)
				(type default)
			)
			(layer "F.Fab")
		)
		(fp_line
			(start 0.12065 -0.2794)
			(end 0.12065 -0.3048)
			(stroke
				(width 0.1)
				(type default)
			)
			(layer "F.Fab")
		)
		(fp_line
			(start 0.12065 -0.3048)
			(end 0.67945 -0.3048)
			(stroke
				(width 0.1)
				(type default)
			)
			(layer "F.Fab")
		)
		(fp_line
			(start 0.67945 -0.3048)
			(end 0.67945 0.3048)
			(stroke
				(width 0.1)
				(type default)
			)
			(layer "F.Fab")
		)
		(fp_line
			(start -0.67945 -0.305054)
			(end -0.12065 -0.305054)
			(stroke
				(width 0.1)
				(type default)
			)
			(layer "F.Fab")
		)
		(fp_line
			(start -0.12065 -0.305054)
			(end -0.12065 -0.2794)
			(stroke
				(width 0.1)
				(type default)
			)
			(layer "F.Fab")
		)
		(pad "1" smd circle
			(at -0.40005 0 270)
			(size 0 0)
			(layers "F.Cu" "F.Mask" "F.Paste")
			(net "PVDD18_S5_P1_EN")
		)
		(pad "2" smd circle
			(at 0.40005 0 270)
			(size 0 0)
			(layers "F.Cu" "F.Mask" "F.Paste")
			(net "GND")
		)
	)
	(footprint ""
		(layer "F.Cu")
		(at 111.506 -413.385)
		(property "Reference" "R586"
			(at 0 0 0)
			(layer "F.SilkS")
			(hide yes)
			(effects
				(font
					(size 1.27 1.27)
				)
			)
		)
		(property "Value" ""
			(at 0 0 0)
			(layer "F.Fab")
			(effects
				(font
					(size 1.27 1.27)
				)
			)
		)
		(duplicate_pad_numbers_are_jumpers no)
		(fp_line
			(start -1.2954 -0.5842)
			(end 1.2954 -0.5842)
			(stroke
				(width 0.1524)
				(type default)
			)
			(layer "F.SilkS")
		)
		(fp_line
			(start -1.2954 0.5842)
			(end -1.2954 -0.5842)
			(stroke
				(width 0.1524)
				(type default)
			)
			(layer "F.SilkS")
		)
		(fp_line
			(start 1.2954 -0.5842)
			(end 1.2954 0.5842)
			(stroke
				(width 0.1524)
				(type default)
			)
			(layer "F.SilkS")
		)
		(fp_line
			(start 1.2954 0.5842)
			(end -1.2954 0.5842)
			(stroke
				(width 0.1524)
				(type default)
			)
			(layer "F.SilkS")
		)
		(fp_line
			(start -1.1938 -0.406654)
			(end -0.8636 -0.406654)
			(stroke
				(width 0.1)
				(type default)
			)
			(layer "F.Fab")
		)
		(fp_line
			(start -1.1938 0.4064)
			(end -1.1938 -0.406654)
			(stroke
				(width 0.1)
				(type default)
			)
			(layer "F.Fab")
		)
		(fp_line
			(start -0.8636 -0.4572)
			(end 0.8636 -0.4572)
			(stroke
				(width 0.1)
				(type default)
			)
			(layer "F.Fab")
		)
		(fp_line
			(start -0.8636 -0.406654)
			(end -0.8636 -0.4572)
			(stroke
				(width 0.1)
				(type default)
			)
			(layer "F.Fab")
		)
		(fp_line
			(start -0.8636 0.4064)
			(end -1.1938 0.4064)
			(stroke
				(width 0.1)
				(type default)
			)
			(layer "F.Fab")
		)
		(fp_line
			(start -0.8636 0.4318)
			(end -0.8636 0.4064)
			(stroke
				(width 0.1)
				(type default)
			)
			(layer "F.Fab")
		)
		(fp_line
			(start -0.8636 0.4572)
			(end -0.8636 0.4318)
			(stroke
				(width 0.1)
				(type default)
			)
			(layer "F.Fab")
		)
		(fp_line
			(start 0.8636 -0.4572)
			(end 0.8636 -0.406654)
			(stroke
				(width 0.1)
				(type default)
			)
			(layer "F.Fab")
		)
		(fp_line
			(start 0.8636 -0.406654)
			(end 1.1938 -0.406654)
			(stroke
				(width 0.1)
				(type default)
			)
			(layer "F.Fab")
		)
		(fp_line
			(start 0.8636 0.4064)
			(end 0.8636 0.4572)
			(stroke
				(width 0.1)
				(type default)
			)
			(layer "F.Fab")
		)
		(fp_line
			(start 0.8636 0.4572)
			(end -0.8636 0.4572)
			(stroke
				(width 0.1)
				(type default)
			)
			(layer "F.Fab")
		)
		(fp_line
			(start 1.1938 -0.406654)
			(end 1.1938 0.4064)
			(stroke
				(width 0.1)
				(type default)
			)
			(layer "F.Fab")
		)
		(fp_line
			(start 1.1938 0.4064)
			(end 0.8636 0.4064)
			(stroke
				(width 0.1)
				(type default)
			)
			(layer "F.Fab")
		)
		(pad "1" smd rect
			(at -0.7366 0 270)
			(size 0.7112 0.8128)
			(layers "F.Cu" "F.Mask" "F.Paste")
			(net "P3V3_9ZXL045_P1")
		)
		(pad "2" smd rect
			(at 0.7366 0 270)
			(size 0.7112 0.8128)
			(layers "F.Cu" "F.Mask" "F.Paste")
			(net "P3V3_9ZXL045_P1_VDDA")
		)
	)
)
